FILE_TYPE = CONNECTIVITY;
{Allegro Design Entry HDL 17.2-2016 S081 (4005846) 1/11/2022}
"PAGE_NUMBER" = 289;
0"NC";
1"GND\g";
2"GND\g";
3"GND\g";
4"GND\g";
5"GND\g";
6"GND\g";
7"GND\g";
8"GND\g";
9"GND\g";
10"GND\g";
11"GND\g";
12"GND\g";
13"GND\g";
14"GND\g";
15"GND\g";
16"GND\g";
17"GND\g";
18"GND\g";
19"GND\g";
20"GND\g";
21"GND\g";
22"GND\g";
23"GND\g";
24"GND\g";
25"GND\g";
26"GND\g";
27"GND\g";
28"GND\g";
29"GND\g";
30"GND\g";
31"GND\g";
32"GND\g";
33"GND\g";
34"GND\g";
35"GND\g";
%"HOLE"
"1","(3100,1175)","0","pure_quanta","I10";
;
PART_NUMBER"TMP-Q_HOLE78"
MATERIAL"EMPTY"
PACK_TYPE"TH"
$LOCATION"H36"
NEEDS_NO_SIZE"TRUE"
CDS_LIB"pure_quanta"
CDS_LOCATION"H36"
$SEC"1"
CDS_SEC"1";
"1 \B"
$PN"1"0;
%"UNIVERSAL_GND"
"1","(500,900)","0","logical_power","I100";
;
CDS_LIB"logical_power"
HDL_POWER"GND";
"A"32;
%"UNIVERSAL_GND"
"1","(1050,900)","0","logical_power","I101";
;
CDS_LIB"logical_power"
HDL_POWER"GND";
"A"5;
%"HOLE"
"1","(775,2275)","0","pure_quanta","I11";
;
PART_NUMBER"DUMMY50"
PACK_TYPE"TH"
MATERIAL"EMPTY"
$LOCATION"H28"
CDS_LIB"pure_quanta"
NEEDS_NO_SIZE"TRUE"
CDS_LOCATION"H28"
$SEC"1"
CDS_SEC"1";
"1 \B"
$PN"1"0;
%"HOLE"
"1","(275,2275)","0","pure_quanta","I12";
;
PART_NUMBER"DUMMY50"
MATERIAL"EMPTY"
PACK_TYPE"TH"
$LOCATION"H27"
CDS_LIB"pure_quanta"
NEEDS_NO_SIZE"TRUE"
CDS_LOCATION"H27"
$SEC"1"
CDS_SEC"1";
"1 \B"
$PN"1"0;
%"HOLE"
"1","(-2475,4400)","0","pure_quanta","I140";
;
PART_NUMBER"HOLE596"
PACK_TYPE"TH"
MATERIAL"EMPTY"
$LOCATION"H86"
NEEDS_NO_SIZE"TRUE"
CDS_LIB"pure_quanta"
CDS_LOCATION"H86"
$SEC"1"
CDS_SEC"1";
"1 \B"
$PN"1"20;
%"UNIVERSAL_GND"
"1","(-2750,4025)","0","logical_power","I141";
;
HDL_POWER"GND"
CDS_LIB"logical_power";
"A"20;
%"HOLE"
"1","(-1775,4400)","0","pure_quanta","I144";
;
PART_NUMBER"HOLE596"
PACK_TYPE"TH"
MATERIAL"EMPTY"
$LOCATION"H88"
NEEDS_NO_SIZE"TRUE"
CDS_LIB"pure_quanta"
CDS_LOCATION"H88"
$SEC"1"
CDS_SEC"1";
"1 \B"
$PN"1"19;
%"UNIVERSAL_GND"
"1","(-2050,4025)","0","logical_power","I145";
;
HDL_POWER"GND"
CDS_LIB"logical_power";
"A"19;
%"UNIVERSAL_GND"
"1","(-1375,4025)","0","logical_power","I146";
;
HDL_POWER"GND"
CDS_LIB"logical_power";
"A"18;
%"HOLE"
"1","(-1100,4400)","0","pure_quanta","I147";
;
PART_NUMBER"HOLE596"
PACK_TYPE"TH"
MATERIAL"EMPTY"
$LOCATION"H91"
NEEDS_NO_SIZE"TRUE"
CDS_LIB"pure_quanta"
CDS_LOCATION"H91"
$SEC"1"
CDS_SEC"1";
"1 \B"
$PN"1"18;
%"HOLE"
"1","(-425,4400)","0","pure_quanta","I148";
;
PART_NUMBER"HOLE596"
PACK_TYPE"TH"
MATERIAL"EMPTY"
$LOCATION"H93"
NEEDS_NO_SIZE"TRUE"
CDS_LIB"pure_quanta"
CDS_LOCATION"H93"
$SEC"1"
CDS_SEC"1";
"1 \B"
$PN"1"17;
%"HOLE"
"1","(925,4400)","0","pure_quanta","I149";
;
PART_NUMBER"HOLE596"
PACK_TYPE"TH"
MATERIAL"EMPTY"
$LOCATION"H97"
NEEDS_NO_SIZE"TRUE"
CDS_LIB"pure_quanta"
CDS_LOCATION"H97"
$SEC"1"
CDS_SEC"1";
"1 \B"
$PN"1"15;
%"HOLE"
"1","(250,4400)","0","pure_quanta","I150";
;
PART_NUMBER"HOLE596"
PACK_TYPE"TH"
MATERIAL"EMPTY"
$LOCATION"H95"
NEEDS_NO_SIZE"TRUE"
CDS_LIB"pure_quanta"
CDS_LOCATION"H95"
$SEC"1"
CDS_SEC"1";
"1 \B"
$PN"1"16;
%"UNIVERSAL_GND"
"1","(650,4025)","0","logical_power","I151";
;
HDL_POWER"GND"
CDS_LIB"logical_power";
"A"15;
%"UNIVERSAL_GND"
"1","(-25,4025)","0","logical_power","I152";
;
HDL_POWER"GND"
CDS_LIB"logical_power";
"A"16;
%"UNIVERSAL_GND"
"1","(-700,4025)","0","logical_power","I153";
;
HDL_POWER"GND"
CDS_LIB"logical_power";
"A"17;
%"HOLE"
"1","(2300,4425)","0","pure_quanta","I154";
;
PART_NUMBER"HOLE596"
PACK_TYPE"TH"
MATERIAL"EMPTY"
$LOCATION"H101"
NEEDS_NO_SIZE"TRUE"
CDS_LIB"pure_quanta"
CDS_LOCATION"H101"
$SEC"1"
CDS_SEC"1";
"1 \B"
$PN"1"27;
%"HOLE"
"1","(1625,4425)","0","pure_quanta","I155";
;
PART_NUMBER"HOLE596"
PACK_TYPE"TH"
MATERIAL"EMPTY"
$LOCATION"H99"
NEEDS_NO_SIZE"TRUE"
CDS_LIB"pure_quanta"
CDS_LOCATION"H99"
$SEC"1"
CDS_SEC"1";
"1 \B"
$PN"1"14;
%"UNIVERSAL_GND"
"1","(2025,4050)","0","logical_power","I156";
;
HDL_POWER"GND"
CDS_LIB"logical_power";
"A"27;
%"UNIVERSAL_GND"
"1","(1350,4050)","0","logical_power","I157";
;
HDL_POWER"GND"
CDS_LIB"logical_power";
"A"14;
%"HOLE"
"1","(2300,3550)","0","pure_quanta","I158";
;
PART_NUMBER"HOLE596"
PACK_TYPE"TH"
MATERIAL"EMPTY"
$LOCATION"H102"
NEEDS_NO_SIZE"TRUE"
CDS_LIB"pure_quanta"
CDS_LOCATION"H102"
$SEC"1"
CDS_SEC"1";
"1 \B"
$PN"1"28;
%"HOLE"
"1","(1625,3550)","0","pure_quanta","I159";
;
PART_NUMBER"HOLE596"
MATERIAL"EMPTY"
PACK_TYPE"TH"
$LOCATION"H100"
CDS_LIB"pure_quanta"
NEEDS_NO_SIZE"TRUE"
CDS_LOCATION"H100"
$SEC"1"
CDS_SEC"1";
"1 \B"
$PN"1"21;
%"HOLE"
"1","(925,3525)","0","pure_quanta","I160";
;
PART_NUMBER"HOLE596"
PACK_TYPE"TH"
MATERIAL"EMPTY"
$LOCATION"H98"
NEEDS_NO_SIZE"TRUE"
CDS_LIB"pure_quanta"
CDS_LOCATION"H98"
$SEC"1"
CDS_SEC"1";
"1 \B"
$PN"1"22;
%"HOLE"
"1","(250,3525)","0","pure_quanta","I161";
;
PART_NUMBER"HOLE596"
PACK_TYPE"TH"
MATERIAL"EMPTY"
$LOCATION"H96"
NEEDS_NO_SIZE"TRUE"
CDS_LIB"pure_quanta"
CDS_LOCATION"H96"
$SEC"1"
CDS_SEC"1";
"1 \B"
$PN"1"23;
%"UNIVERSAL_GND"
"1","(1350,3175)","0","logical_power","I162";
;
CDS_LIB"logical_power"
HDL_POWER"GND";
"A"21;
%"UNIVERSAL_GND"
"1","(2025,3175)","0","logical_power","I163";
;
HDL_POWER"GND"
CDS_LIB"logical_power";
"A"28;
%"UNIVERSAL_GND"
"1","(650,3075)","0","logical_power","I164";
;
CDS_LIB"logical_power"
HDL_POWER"GND";
"A"22;
%"HOLE"
"1","(-425,3525)","0","pure_quanta","I165";
;
PART_NUMBER"HOLE596"
MATERIAL"EMPTY"
PACK_TYPE"TH"
$LOCATION"H94"
NEEDS_NO_SIZE"TRUE"
CDS_LIB"pure_quanta"
CDS_LOCATION"H94"
$SEC"1"
CDS_SEC"1";
"1 \B"
$PN"1"24;
%"HOLE"
"1","(-1100,3525)","0","pure_quanta","I166";
;
PART_NUMBER"HOLE596"
MATERIAL"EMPTY"
PACK_TYPE"TH"
$LOCATION"H92"
NEEDS_NO_SIZE"TRUE"
CDS_LIB"pure_quanta"
CDS_LOCATION"H92"
$SEC"1"
CDS_SEC"1";
"1 \B"
$PN"1"25;
%"HOLE"
"1","(-1775,3525)","0","pure_quanta","I167";
;
PART_NUMBER"HOLE596"
PACK_TYPE"TH"
MATERIAL"EMPTY"
$LOCATION"H89"
NEEDS_NO_SIZE"TRUE"
CDS_LIB"pure_quanta"
CDS_LOCATION"H89"
$SEC"1"
CDS_SEC"1";
"1 \B"
$PN"1"26;
%"HOLE"
"1","(-2475,3525)","0","pure_quanta","I168";
;
PART_NUMBER"HOLE596"
MATERIAL"EMPTY"
PACK_TYPE"TH"
$LOCATION"H87"
NEEDS_NO_SIZE"TRUE"
CDS_LIB"pure_quanta"
CDS_LOCATION"H87"
$SEC"1"
CDS_SEC"1";
"1 \B"
$PN"1"31;
%"UNIVERSAL_GND"
"1","(-25,3075)","0","logical_power","I169";
;
CDS_LIB"logical_power"
HDL_POWER"GND";
"A"23;
%"UNIVERSAL_GND"
"1","(-700,3075)","0","logical_power","I170";
;
CDS_LIB"logical_power"
HDL_POWER"GND";
"A"24;
%"UNIVERSAL_GND"
"1","(-1375,3075)","0","logical_power","I171";
;
CDS_LIB"logical_power"
HDL_POWER"GND";
"A"25;
%"UNIVERSAL_GND"
"1","(-2050,3075)","0","logical_power","I172";
;
CDS_LIB"logical_power"
HDL_POWER"GND";
"A"26;
%"UNIVERSAL_GND"
"1","(-2750,3150)","0","logical_power","I173";
;
HDL_POWER"GND"
CDS_LIB"logical_power";
"A"31;
%"HOLE"
"1","(3025,4425)","0","pure_quanta","I174";
;
PART_NUMBER"HOLE596"
PACK_TYPE"TH"
MATERIAL"EMPTY"
$LOCATION"H103"
NEEDS_NO_SIZE"TRUE"
CDS_LIB"pure_quanta"
CDS_LOCATION"H103"
$SEC"1"
CDS_SEC"1";
"1 \B"
$PN"1"30;
%"HOLE"
"1","(3025,3550)","0","pure_quanta","I175";
;
PART_NUMBER"HOLE596"
PACK_TYPE"TH"
MATERIAL"EMPTY"
$LOCATION"H104"
NEEDS_NO_SIZE"TRUE"
CDS_LIB"pure_quanta"
CDS_LOCATION"H104"
$SEC"1"
CDS_SEC"1";
"1 \B"
$PN"1"29;
%"UNIVERSAL_GND"
"1","(2750,4050)","0","logical_power","I176";
;
HDL_POWER"GND"
CDS_LIB"logical_power";
"A"30;
%"UNIVERSAL_GND"
"1","(2750,3175)","0","logical_power","I177";
;
HDL_POWER"GND"
CDS_LIB"logical_power";
"A"29;
%"HOLE"
"1","(775,1050)","0","pure_quanta","I18";
;
PART_NUMBER"HOLE1187"
PACK_TYPE"TH"
MATERIAL"EMPTY"
$LOCATION"H76"
CDS_LIB"pure_quanta"
NEEDS_NO_SIZE"TRUE"
CDS_LOCATION"H76"
$SEC"1"
CDS_SEC"1";
"1 \B"
$PN"1"32;
%"HOLE"
"1","(0,750)","0","pure_quanta","I19";
;
PART_NUMBER"HOLE1079"
MATERIAL"EMPTY"
PACK_TYPE"TH"
$LOCATION"H26"
CDS_LIB"pure_quanta"
NEEDS_NO_SIZE"TRUE"
CDS_LOCATION"H26"
$SEC"1"
CDS_SEC"1";
"1 \B"
$PN"1"0;
%"HOLE"
"1","(3675,3550)","0","pure_quanta","I190";
;
PART_NUMBER"HOLE596"
MATERIAL"EMPTY"
PACK_TYPE"TH"
$LOCATION"H106"
NEEDS_NO_SIZE"TRUE"
CDS_LIB"pure_quanta"
CDS_LOCATION"H106"
$SEC"1"
CDS_SEC"1";
"1 \B"
$PN"1"35;
%"UNIVERSAL_GND"
"1","(3400,3175)","0","logical_power","I191";
;
HDL_POWER"GND"
CDS_LIB"logical_power";
"A"35;
%"HOLE"
"1","(3675,4425)","0","pure_quanta","I192";
;
PART_NUMBER"HOLE596"
MATERIAL"EMPTY"
PACK_TYPE"TH"
$LOCATION"H105"
CDS_LIB"pure_quanta"
NEEDS_NO_SIZE"TRUE"
CDS_LOCATION"H105"
$SEC"1"
CDS_SEC"1";
"1 \B"
$PN"1"33;
%"UNIVERSAL_GND"
"1","(3400,4050)","0","logical_power","I193";
;
HDL_POWER"GND"
CDS_LIB"logical_power";
"A"33;
%"HOLE"
"1","(-500,750)","0","pure_quanta","I20";
;
PART_NUMBER"HOLE1079"
MATERIAL"EMPTY"
PACK_TYPE"TH"
$LOCATION"H24"
CDS_LIB"pure_quanta"
NEEDS_NO_SIZE"TRUE"
CDS_LOCATION"H24"
$SEC"1"
CDS_SEC"1";
"1 \B"
$PN"1"0;
%"GND_HOLE"
"1","(1350,-525)","0","pure_quanta","I202";
;
PART_NUMBER"GND_HOLE514"
MATERIAL"EMPTY"
PACK_TYPE"TH"
$LOCATION"H115"
CDS_LIB"pure_quanta"
NEEDS_NO_SIZE"TRUE"
CDS_LOCATION"H115"
$SEC"1"
CDS_SEC"1";
"GND5"
$PN"5"1;
"GND6"
$PN"6"1;
"GND2"
$PN"2"1;
"GND3"
$PN"3"1;
"GND7"
$PN"7"1;
"GND8"
$PN"8"1;
"GND9"
$PN"9"1;
"GND4"
$PN"4"1;
%"UNIVERSAL_GND"
"1","(1075,-925)","0","logical_power","I203";
;
CDS_LIB"logical_power"
HDL_POWER"GND";
"A"1;
%"GND_HOLE"
"1","(-2325,-525)","0","pure_quanta","I204";
;
PART_NUMBER"GND_HOLE140"
PACK_TYPE"TH"
MATERIAL"EMPTY"
$LOCATION"H111"
NEEDS_NO_SIZE"TRUE"
CDS_LIB"pure_quanta"
CDS_LOCATION"H111"
$SEC"1"
CDS_SEC"1";
"GND5"
$PN"5"6;
"GND6"
$PN"6"6;
"GND2"
$PN"2"6;
"GND3"
$PN"3"6;
"GND7"
$PN"7"6;
"GND8"
$PN"8"6;
"GND9"
$PN"9"6;
"GND4"
$PN"4"6;
%"UNIVERSAL_GND"
"1","(-2600,-925)","0","logical_power","I205";
;
HDL_POWER"GND"
CDS_LIB"logical_power";
"A"6;
%"UNIVERSAL_GND"
"1","(-1825,-925)","0","logical_power","I206";
;
CDS_LIB"logical_power"
HDL_POWER"GND";
"A"7;
%"GND_HOLE"
"1","(-1550,-525)","0","pure_quanta","I207";
;
PART_NUMBER"GND_HOLE140"
MATERIAL"EMPTY"
PACK_TYPE"TH"
$LOCATION"H112"
CDS_LIB"pure_quanta"
NEEDS_NO_SIZE"TRUE"
CDS_LOCATION"H112"
$SEC"1"
CDS_SEC"1";
"GND5"
$PN"5"7;
"GND6"
$PN"6"7;
"GND2"
$PN"2"7;
"GND3"
$PN"3"7;
"GND7"
$PN"7"7;
"GND8"
$PN"8"7;
"GND9"
$PN"9"7;
"GND4"
$PN"4"7;
%"HOLE"
"1","(-1025,750)","0","pure_quanta","I21";
;
PART_NUMBER"HOLE1079"
MATERIAL"EMPTY"
PACK_TYPE"TH"
$LOCATION"H22"
CDS_LIB"pure_quanta"
NEEDS_NO_SIZE"TRUE"
CDS_LOCATION"H22"
$SEC"1"
CDS_SEC"1";
"1 \B"
$PN"1"0;
%"HOLE"
"1","(-2450,2250)","0","pure_quanta","I216";
;
PART_NUMBER"SP_HOLE1199"
MATERIAL"EMPTY"
PACK_TYPE"TH"
LOCATION"H44"
NEEDS_NO_SIZE"TRUE"
CDS_LIB"pure_quanta"
$SEC"1"
CDS_SEC"1";
"1 \B"
$PN"1"13;
%"HOLE"
"1","(-1825,2250)","0","pure_quanta","I217";
;
PART_NUMBER"SP_HOLE1199"
MATERIAL"EMPTY"
PACK_TYPE"TH"
LOCATION"H45"
CDS_LIB"pure_quanta"
NEEDS_NO_SIZE"TRUE"
$SEC"1"
CDS_SEC"1";
"1 \B"
$PN"1"12;
%"HOLE"
"1","(-1175,2250)","0","pure_quanta","I218";
;
PART_NUMBER"SP_HOLE1199"
PACK_TYPE"TH"
MATERIAL"EMPTY"
LOCATION"H47"
NEEDS_NO_SIZE"TRUE"
CDS_LIB"pure_quanta"
$SEC"1"
CDS_SEC"1";
"1 \B"
$PN"1"10;
%"HOLE"
"1","(-525,2250)","0","pure_quanta","I219";
;
PART_NUMBER"SP_HOLE1199"
MATERIAL"EMPTY"
PACK_TYPE"TH"
LOCATION"H49"
CDS_LIB"pure_quanta"
NEEDS_NO_SIZE"TRUE"
$SEC"1"
CDS_SEC"1";
"1 \B"
$PN"1"11;
%"UNIVERSAL_GND"
"1","(-2725,2100)","0","logical_power","I220";
;
CDS_LIB"logical_power"
HDL_POWER"GND";
"A"13;
%"UNIVERSAL_GND"
"1","(-2100,2100)","0","logical_power","I221";
;
CDS_LIB"logical_power"
HDL_POWER"GND";
"A"12;
%"UNIVERSAL_GND"
"1","(-1450,2100)","0","logical_power","I222";
;
HDL_POWER"GND"
CDS_LIB"logical_power";
"A"10;
%"UNIVERSAL_GND"
"1","(-800,2100)","0","logical_power","I223";
;
HDL_POWER"GND"
CDS_LIB"logical_power";
"A"11;
%"HOLE"
"1","(2750,-825)","0","pure_quanta","I224";
;
PART_NUMBER"TMP-C_T2I_ALEX_1121_1"
PACK_TYPE"TH"
MATERIAL"EMPTY"
$LOCATION"H120"
CDS_LIB"pure_quanta"
NEEDS_NO_SIZE"TRUE"
CDS_LOCATION"H120"
$SEC"1"
CDS_SEC"1";
"1 \B"
$PN"1"0;
%"HOLE"
"1","(3500,-850)","0","pure_quanta","I225";
;
PART_NUMBER"TMP-C_T2I_ALEX_1121_1"
PACK_TYPE"TH"
MATERIAL"EMPTY"
$LOCATION"H122"
NEEDS_NO_SIZE"TRUE"
CDS_LIB"pure_quanta"
CDS_LOCATION"H122"
$SEC"1"
CDS_SEC"1";
"1 \B"
$PN"1"0;
%"HOLE"
"1","(4275,-850)","0","pure_quanta","I226";
;
PART_NUMBER"TMP-C_T2I_ALEX_1121_1"
PACK_TYPE"TH"
MATERIAL"EMPTY"
$LOCATION"H124"
NEEDS_NO_SIZE"TRUE"
CDS_LIB"pure_quanta"
CDS_LOCATION"H124"
$SEC"1"
CDS_SEC"1";
"1 \B"
$PN"1"0;
%"HOLE"
"1","(5050,-850)","0","pure_quanta","I227";
;
PART_NUMBER"TMP-C_T2I_ALEX_1121_1"
PACK_TYPE"TH"
MATERIAL"EMPTY"
$LOCATION"H126"
NEEDS_NO_SIZE"TRUE"
CDS_LIB"pure_quanta"
CDS_LOCATION"H126"
$SEC"1"
CDS_SEC"1";
"1 \B"
$PN"1"0;
%"HOLE"
"1","(5075,-375)","0","pure_quanta","I228";
;
PART_NUMBER"TMP-C_T2I_ALEX_1121_1"
MATERIAL"EMPTY"
PACK_TYPE"TH"
$LOCATION"H127"
CDS_LIB"pure_quanta"
NEEDS_NO_SIZE"TRUE"
CDS_LOCATION"H127"
$SEC"1"
CDS_SEC"1";
"1 \B"
$PN"1"0;
%"HOLE"
"1","(4300,-375)","0","pure_quanta","I229";
;
PART_NUMBER"TMP-C_T2I_ALEX_1121_1"
MATERIAL"EMPTY"
PACK_TYPE"TH"
$LOCATION"H125"
CDS_LIB"pure_quanta"
NEEDS_NO_SIZE"TRUE"
CDS_LOCATION"H125"
$SEC"1"
CDS_SEC"1";
"1 \B"
$PN"1"0;
%"HOLE"
"1","(4350,4425)","0","pure_quanta","I232";
;
PART_NUMBER"HOLE596"
MATERIAL"EMPTY"
PACK_TYPE"TH"
$LOCATION"H128"
NEEDS_NO_SIZE"TRUE"
CDS_LIB"pure_quanta"
CDS_LOCATION"H128"
$SEC"1"
CDS_SEC"1";
"1 \B"
$PN"1"34;
%"UNIVERSAL_GND"
"1","(4075,4050)","0","logical_power","I233";
;
CDS_LIB"logical_power"
HDL_POWER"GND";
"A"34;
%"CONN1_10165288101LF"
"1","(4150,3250)","0","pure_quanta","I238";
;
PART_NUMBER"DFHS03FR030"
VALUE"CONN1_10165288-101LF"
MATERIAL"IO"
PART_TYPE"THLF"
$LOCATION"J122"
CDS_LIB"pure_quanta"
NEEDS_NO_SIZE"TRUE"
CDS_LMAN_SYM_OUTLINE"-50,125,50,-125"
CDS_LOCATION"J122"
$SEC"1"
CDS_SEC"1";
"NC1"
$PN"SCR_H1"0;
%"CONN1_10165288101LF"
"1","(5150,3250)","0","pure_quanta","I239";
;
PART_NUMBER"DFHS03FR030"
VALUE"CONN1_10165288-101LF"
PART_TYPE"THLF"
MATERIAL"IO"
$LOCATION"J123"
CDS_LIB"pure_quanta"
CDS_LMAN_SYM_OUTLINE"-50,125,50,-125"
NEEDS_NO_SIZE"TRUE"
CDS_LOCATION"J123"
$SEC"1"
CDS_SEC"1";
"NC1"
$PN"SCR_H1"0;
%"UNIVERSAL_GND"
"1","(50,-925)","0","logical_power","I243";
;
HDL_POWER"GND"
CDS_LIB"logical_power";
"A"2;
%"UNIVERSAL_GND"
"1","(-725,-925)","0","logical_power","I244";
;
CDS_LIB"logical_power"
HDL_POWER"GND";
"A"3;
%"UNIVERSAL_GND"
"1","(5125,1000)","0","logical_power","I245";
;
CDS_LIB"logical_power"
HDL_POWER"GND";
"A"4;
%"GND_HOLE"
"1","(-450,-525)","0","pure_quanta","I247";
;
PART_NUMBER"TMP-QGND_HOLE12"
MATERIAL"EMPTY"
PACK_TYPE"TH"
LOCATION"H113"
CDS_LIB"pure_quanta"
NEEDS_NO_SIZE"TRUE"
$SEC"1"
CDS_SEC"1";
"GND5"
$PN"5"3;
"GND6"
$PN"6"3;
"GND2"
$PN"2"3;
"GND3"
$PN"3"3;
"GND7"
$PN"7"3;
"GND8"
$PN"8"3;
"GND9"
$PN"9"3;
"GND4"
$PN"4"3;
%"GND_HOLE"
"1","(325,-525)","0","pure_quanta","I248";
;
PART_NUMBER"TMP-QGND_HOLE12"
PACK_TYPE"TH"
MATERIAL"EMPTY"
LOCATION"H114"
NEEDS_NO_SIZE"TRUE"
CDS_LIB"pure_quanta"
$SEC"1"
CDS_SEC"1";
"GND5"
$PN"5"2;
"GND6"
$PN"6"2;
"GND2"
$PN"2"2;
"GND3"
$PN"3"2;
"GND7"
$PN"7"2;
"GND8"
$PN"8"2;
"GND9"
$PN"9"2;
"GND4"
$PN"4"2;
%"HOLE"
"1","(5400,1150)","0","pure_quanta","I249";
;
PART_NUMBER"HOLE1195"
PACK_TYPE"TH"
MATERIAL"EMPTY"
LOCATION"H129"
NEEDS_NO_SIZE"TRUE"
CDS_LIB"pure_quanta"
$SEC"1"
CDS_SEC"1";
"1 \B"
$PN"1"4;
%"HOLE"
"1","(5275,4050)","0","pure_quanta","I254";
;
PART_NUMBER"HOLE372"
MATERIAL"EMPTY"
PACK_TYPE"TH"
LOCATION"H90"
CDS_LIB"pure_quanta"
NEEDS_NO_SIZE"TRUE"
$SEC"1"
CDS_SEC"1";
"1 \B"
$PN"1"0;
%"HOLE"
"1","(4375,2150)","0","pure_quanta","I54";
;
PART_NUMBER"HOLE1248"
MATERIAL"EMPTY"
PACK_TYPE"TH"
$LOCATION"H32"
NEEDS_NO_SIZE"TRUE"
CDS_LIB"pure_quanta"
CDS_LOCATION"H32"
$SEC"1"
CDS_SEC"1";
"1 \B"
$PN"1"9;
%"UNIVERSAL_GND"
"1","(4100,2000)","0","logical_power","I55";
;
HDL_POWER"GND"
CDS_LIB"logical_power";
"A"9;
%"HOLE"
"1","(3875,2150)","0","pure_quanta","I56";
;
PART_NUMBER"HOLE1248"
PACK_TYPE"TH"
MATERIAL"EMPTY"
$LOCATION"H31"
NEEDS_NO_SIZE"TRUE"
CDS_LIB"pure_quanta"
CDS_LOCATION"H31"
$SEC"1"
CDS_SEC"1";
"1 \B"
$PN"1"8;
%"HOLE"
"1","(3050,2225)","0","pure_quanta","I57";
;
PART_NUMBER"HOLE1247"
MATERIAL"EMPTY"
PACK_TYPE"TH"
$LOCATION"H75"
NEEDS_NO_SIZE"TRUE"
CDS_LIB"pure_quanta"
CDS_LOCATION"H75"
$SEC"1"
CDS_SEC"1";
"1 \B"
$PN"1"0;
%"HOLE"
"1","(2550,2225)","0","pure_quanta","I58";
;
PART_NUMBER"HOLE1247"
MATERIAL"EMPTY"
PACK_TYPE"TH"
$LOCATION"H74"
NEEDS_NO_SIZE"TRUE"
CDS_LIB"pure_quanta"
CDS_LOCATION"H74"
$SEC"1"
CDS_SEC"1";
"1 \B"
$PN"1"0;
%"UNIVERSAL_GND"
"1","(3600,2000)","0","logical_power","I59";
;
CDS_LIB"logical_power"
HDL_POWER"GND";
"A"8;
%"HOLE"
"1","(-1525,750)","0","pure_quanta","I60";
;
PART_NUMBER"HOLE1079"
PACK_TYPE"TH"
MATERIAL"EMPTY"
$LOCATION"H20"
CDS_LIB"pure_quanta"
NEEDS_NO_SIZE"TRUE"
CDS_LOCATION"H20"
$SEC"1"
CDS_SEC"1";
"1 \B"
$PN"1"0;
%"HOLE"
"1","(-2025,750)","0","pure_quanta","I61";
;
PART_NUMBER"HOLE1079"
PACK_TYPE"TH"
MATERIAL"EMPTY"
$LOCATION"H18"
CDS_LIB"pure_quanta"
NEEDS_NO_SIZE"TRUE"
CDS_LOCATION"H18"
$SEC"1"
CDS_SEC"1";
"1 \B"
$PN"1"0;
%"HOLE"
"1","(-2525,750)","0","pure_quanta","I63";
;
PART_NUMBER"HOLE1079"
PACK_TYPE"TH"
MATERIAL"EMPTY"
$LOCATION"H16"
CDS_LIB"pure_quanta"
NEEDS_NO_SIZE"TRUE"
CDS_LOCATION"H16"
$SEC"1"
CDS_SEC"1";
"1 \B"
$PN"1"0;
%"HOLE"
"1","(25,1250)","0","pure_quanta","I64";
;
PART_NUMBER"HOLE1079"
MATERIAL"EMPTY"
PACK_TYPE"TH"
$LOCATION"H25"
NEEDS_NO_SIZE"TRUE"
CDS_LIB"pure_quanta"
CDS_LOCATION"H25"
$SEC"1"
CDS_SEC"1";
"1 \B"
$PN"1"0;
%"HOLE"
"1","(1800,2275)","0","pure_quanta","I7";
;
PART_NUMBER"DUMMY50"
PACK_TYPE"TH"
MATERIAL"EMPTY"
$LOCATION"H30"
NEEDS_NO_SIZE"TRUE"
CDS_LIB"pure_quanta"
CDS_LOCATION"H30"
$SEC"1"
CDS_SEC"1";
"1 \B"
$PN"1"0;
%"HOLE"
"1","(-475,1250)","0","pure_quanta","I72";
;
PART_NUMBER"HOLE1079"
PACK_TYPE"TH"
MATERIAL"EMPTY"
$LOCATION"H23"
NEEDS_NO_SIZE"TRUE"
CDS_LIB"pure_quanta"
CDS_LOCATION"H23"
$SEC"1"
CDS_SEC"1";
"1 \B"
$PN"1"0;
%"HOLE"
"1","(-1000,1250)","0","pure_quanta","I73";
;
PART_NUMBER"HOLE1079"
MATERIAL"EMPTY"
PACK_TYPE"TH"
$LOCATION"H21"
NEEDS_NO_SIZE"TRUE"
CDS_LIB"pure_quanta"
CDS_LOCATION"H21"
$SEC"1"
CDS_SEC"1";
"1 \B"
$PN"1"0;
%"HOLE"
"1","(-1500,1250)","0","pure_quanta","I74";
;
PART_NUMBER"HOLE1079"
MATERIAL"EMPTY"
PACK_TYPE"TH"
$LOCATION"H19"
NEEDS_NO_SIZE"TRUE"
CDS_LIB"pure_quanta"
CDS_LOCATION"H19"
$SEC"1"
CDS_SEC"1";
"1 \B"
$PN"1"0;
%"HOLE"
"1","(-2000,1250)","0","pure_quanta","I75";
;
PART_NUMBER"HOLE1079"
PACK_TYPE"TH"
MATERIAL"EMPTY"
$LOCATION"H17"
NEEDS_NO_SIZE"TRUE"
CDS_LIB"pure_quanta"
CDS_LOCATION"H17"
$SEC"1"
CDS_SEC"1";
"1 \B"
$PN"1"0;
%"HOLE"
"1","(1300,2275)","0","pure_quanta","I8";
;
PART_NUMBER"DUMMY50"
PACK_TYPE"TH"
MATERIAL"EMPTY"
$LOCATION"H29"
NEEDS_NO_SIZE"TRUE"
CDS_LIB"pure_quanta"
CDS_LOCATION"H29"
$SEC"1"
CDS_SEC"1";
"1 \B"
$PN"1"0;
%"HOLE"
"1","(-2500,1250)","0","pure_quanta","I83";
;
PART_NUMBER"HOLE1079"
PACK_TYPE"TH"
MATERIAL"EMPTY"
$LOCATION"H15"
CDS_LIB"pure_quanta"
NEEDS_NO_SIZE"TRUE"
CDS_LOCATION"H15"
$SEC"1"
CDS_SEC"1";
"1 \B"
$PN"1"0;
%"HOLE"
"1","(1325,1050)","0","pure_quanta","I87";
;
PART_NUMBER"HOLE1187"
MATERIAL"EMPTY"
PACK_TYPE"TH"
$LOCATION"H77"
CDS_LIB"pure_quanta"
NEEDS_NO_SIZE"TRUE"
CDS_LOCATION"H77"
$SEC"1"
CDS_SEC"1";
"1 \B"
$PN"1"5;
%"HOLE"
"1","(3600,1175)","0","pure_quanta","I9";
;
PART_NUMBER"TMP-Q_HOLE78"
MATERIAL"EMPTY"
PACK_TYPE"TH"
$LOCATION"H38"
NEEDS_NO_SIZE"TRUE"
CDS_LIB"pure_quanta"
CDS_LOCATION"H38"
$SEC"1"
CDS_SEC"1";
"1 \B"
$PN"1"0;
END.
